# BASEBOARD_FAB2 (Tioga Pass) — schematic netlist excerpt (pin names and nets, part order shuffled) for the footprints in the layout excerpt that follows; sources: Cadence DE-HDL packaged netlist, KiCad conversion of Wiwynn_Tioga_Pass_MB.brd

R6M8  RES  1.00K 1% CHIP  pkg 0402  page 113 : A = JTAG_MCP_CPU1_TDI_R ; B = JTAG_MCP_CPU1_TDI
C22W35  SC22U16V5MX-4-GP  20%  pkg SMD-BCG5  page 139 : \1\ = P1V5_LAN ; \2\ = GND
R8F36  RES  10.0K 1% CHIP  pkg 0402  page 185 : A = P3V3 ; B = PU_M2_CLK_REQ_N

(kicad_pcb
	(version 20260206)
	(generator "pcbnew")
	(generator_version "10.0")
	(general
		(thickness 1.6)
		(legacy_teardrops no)
	)
	(paper "A4")
	(title_block
		(title "Wiwynn_Tioga_Pass_MB.brd")
		(comment 1 "Tioga Pass / footprints 3676-3678 of 4770")
	)
	(layers
		(0 "F.Cu" signal "TOP")
		(4 "In1.Cu" signal "L2GND")
		(6 "In2.Cu" signal "L3")
		(8 "In3.Cu" signal "L4GND")
		(10 "In4.Cu" signal "L5")
		(12 "In5.Cu" signal "L6GND")
		(14 "In6.Cu" signal "L7VCC")
		(16 "In7.Cu" signal "L8VCC")
		(18 "In8.Cu" signal "L9GND")
		(20 "In9.Cu" signal "L10")
		(22 "In10.Cu" signal "L11GND")
		(24 "In11.Cu" signal "L12")
		(26 "In12.Cu" signal "L13GND")
		(2 "B.Cu" signal "BOTTOM")
		(9 "F.Adhes" user "F.Adhesive")
		(11 "B.Adhes" user "B.Adhesive")
		(13 "F.Paste" user "Package Geometry/Pastemask Top")
		(15 "B.Paste" user "Package Geometry/Pastemask Bottom")
		(5 "F.SilkS" user "Ref Des/Silkscreen Top")
		(7 "B.SilkS" user "Ref Des/Silkscreen Bottom")
		(1 "F.Mask" user "Board Geometry/Soldermask Top")
		(3 "B.Mask" user "Board Geometry/Soldermask Bottom")
		(17 "Dwgs.User" user "User.Drawings")
		(19 "Cmts.User" user "User.Comments")
		(21 "Eco1.User" user "User.Eco1")
		(23 "Eco2.User" user "User.Eco2")
		(25 "Edge.Cuts" user "Board Geometry/Outline")
		(27 "Margin" user)
		(31 "F.CrtYd" user "Package Geometry/Place Bound Top")
		(29 "B.CrtYd" user "Package Geometry/Place Bound Bottom")
		(35 "F.Fab" user "Ref Des/Assembly Top")
		(33 "B.Fab" user "Ref Des/Assembly Bottom")
	)
	(footprint ""
		(layer "B.Cu")
		(at 391.075926 -36.564316 90)
		(property "Reference" "R8F36"
			(at 0 0 90)
			(layer "B.SilkS")
			(hide yes)
			(effects
				(font
					(size 1.27 1.27)
				)
				(justify mirror)
			)
		)
		(property "Value" ""
			(at 0 0 90)
			(layer "B.Fab")
			(effects
				(font
					(size 1.27 1.27)
				)
				(justify mirror)
			)
		)
		(duplicate_pad_numbers_are_jumpers no)
		(fp_poly
			(pts
				(xy 0.2794 -0.1016) (xy -0.2794 -0.1016) (xy -0.2794 0.9906) (xy 0.2794 0.9906)
			)
			(stroke
				(width 0)
				(type default)
			)
			(fill no)
			(layer "B.CrtYd")
		)
		(fp_line
			(start 0.2794 -0.1016)
			(end 0.2794 0.9906)
			(stroke
				(width 0.1)
				(type default)
			)
			(layer "B.Fab")
		)
		(fp_line
			(start -0.2794 -0.1016)
			(end 0.2794 -0.1016)
			(stroke
				(width 0.1)
				(type default)
			)
			(layer "B.Fab")
		)
		(fp_line
			(start 0.2794 0.9906)
			(end -0.2794 0.9906)
			(stroke
				(width 0.1)
				(type default)
			)
			(layer "B.Fab")
		)
		(fp_line
			(start -0.2794 0.9906)
			(end -0.2794 -0.1016)
			(stroke
				(width 0.1)
				(type default)
			)
			(layer "B.Fab")
		)
		(pad "1" smd rect
			(at 0 0 270)
			(size 0.508 0.508)
			(layers "B.Cu" "B.Mask" "B.Paste")
			(net "P3V3")
		)
		(pad "2" smd rect
			(at 0 0.889 270)
			(size 0.508 0.508)
			(layers "B.Cu" "B.Mask" "B.Paste")
			(net "PU_M2_CLK_REQ_N")
		)
		(zone
			(layer "B.Cu")
			(hatch none 0.5)
			(connect_pads
				(clearance 0)
			)
			(min_thickness 0.25)
			(keepout
				(tracks allowed)
				(vias not_allowed)
				(pads allowed)
				(copperpour not_allowed)
				(footprints allowed)
			)
			(placement
				(enabled no)
				(sheetname "")
			)
			(fill
				(thermal_gap 0.5)
				(thermal_bridge_width 0.5)
				(island_removal_mode 0)
			)
			(polygon
				(pts
					(xy 391.329926 -36.818316) (xy 391.329926 -36.310316) (xy 391.710926 -36.310316) (xy 391.710926 -36.818316)
				)
			)
		)
		(zone
			(layer "B.Cu")
			(hatch none 0.5)
			(connect_pads
				(clearance 0)
			)
			(min_thickness 0.25)
			(keepout
				(tracks not_allowed)
				(vias allowed)
				(pads allowed)
				(copperpour not_allowed)
				(footprints allowed)
			)
			(placement
				(enabled no)
				(sheetname "")
			)
			(fill
				(thermal_gap 0.5)
				(thermal_bridge_width 0.5)
				(island_removal_mode 0)
			)
			(polygon
				(pts
					(xy 391.710926 -36.818316) (xy 391.710926 -36.310316) (xy 391.329926 -36.310316) (xy 391.329926 -36.818316)
				)
			)
		)
	)
	(footprint ""
		(layer "B.Cu")
		(at 476.4786 -41.1734 -90)
		(property "Reference" "C22W35"
			(at 0 0 90)
			(layer "B.SilkS")
			(hide yes)
			(effects
				(font
					(size 1.27 1.27)
				)
				(justify mirror)
			)
		)
		(property "Value" "*"
			(at 0.0762 -6.2357 270)
			(unlocked yes)
			(layer "B.Fab")
			(hide yes)
			(effects
				(font
					(size 1.27 1.016)
					(thickness 0.1524)
				)
				(justify mirror)
			)
		)
		(property "Device Type" "SC22U16V5MX-4-GP_SMD-BCG5-SC22A"
			(at 0.0762 -8.2677 270)
			(unlocked yes)
			(layer "B.Fab")
			(hide yes)
			(effects
				(font
					(size 1.27 1.016)
					(thickness 0.1524)
				)
				(justify mirror)
			)
		)
		(duplicate_pad_numbers_are_jumpers no)
		(fp_line
			(start -0.635 0)
			(end 0.635 0)
			(stroke
				(width 0.508)
				(type default)
			)
			(layer "B.SilkS")
		)
		(fp_rect
			(start 0.9652 1.778)
			(end -0.9652 -1.778)
			(stroke
				(width 0)
				(type default)
			)
			(fill no)
			(layer "B.CrtYd")
		)
		(fp_poly
			(pts
				(xy 0.9652 -1.778) (xy -0.9652 -1.778) (xy -0.9652 1.778) (xy 0.9652 1.778)
			)
			(stroke
				(width 0)
				(type default)
			)
			(fill no)
			(layer "B.Fab")
		)
		(pad "1" smd rect
			(at 0 -0.9652 90)
			(size 1.397 1.143)
			(layers "B.Cu" "B.Mask" "B.Paste")
			(net "P1V5_LAN")
		)
		(pad "2" smd rect
			(at 0 0.9652 90)
			(size 1.397 1.143)
			(layers "B.Cu" "B.Mask" "B.Paste")
			(net "GND")
		)
	)
	(footprint ""
		(layer "B.Cu")
		(at 169.418 -125.603 90)
		(property "Reference" "R6M8"
			(at 0 0 90)
			(layer "B.SilkS")
			(hide yes)
			(effects
				(font
					(size 1.27 1.27)
				)
				(justify mirror)
			)
		)
		(property "Value" ""
			(at 0 0 90)
			(layer "B.Fab")
			(effects
				(font
					(size 1.27 1.27)
				)
				(justify mirror)
			)
		)
		(duplicate_pad_numbers_are_jumpers no)
		(fp_rect
			(start -0.2794 0.9906)
			(end 0.2794 -0.1016)
			(stroke
				(width 0)
				(type default)
			)
			(fill no)
			(layer "B.CrtYd")
		)
		(fp_line
			(start 0.2794 -0.1016)
			(end 0.2794 0.9906)
			(stroke
				(width 0.1)
				(type default)
			)
			(layer "B.Fab")
		)
		(fp_line
			(start -0.2794 -0.1016)
			(end 0.2794 -0.1016)
			(stroke
				(width 0.1)
				(type default)
			)
			(layer "B.Fab")
		)
		(fp_line
			(start 0.2794 0.9906)
			(end -0.2794 0.9906)
			(stroke
				(width 0.1)
				(type default)
			)
			(layer "B.Fab")
		)
		(fp_line
			(start -0.2794 0.9906)
			(end -0.2794 -0.1016)
			(stroke
				(width 0.1)
				(type default)
			)
			(layer "B.Fab")
		)
		(pad "1" smd rect
			(at 0 0 270)
			(size 0.508 0.508)
			(layers "B.Cu" "B.Mask" "B.Paste")
			(net "JTAG_MCP_CPU1_TDI_R")
		)
		(pad "2" smd rect
			(at 0 0.889 270)
			(size 0.508 0.508)
			(layers "B.Cu" "B.Mask" "B.Paste")
			(net "JTAG_MCP_CPU1_TDI")
		)
		(zone
			(layer "B.Cu")
			(hatch none 0.5)
			(connect_pads
				(clearance 0)
			)
			(min_thickness 0.25)
			(keepout
				(tracks allowed)
				(vias not_allowed)
				(pads allowed)
				(copperpour not_allowed)
				(footprints allowed)
			)
			(placement
				(enabled no)
				(sheetname "")
			)
			(fill
				(thermal_gap 0.5)
				(thermal_bridge_width 0.5)
				(island_removal_mode 0)
			)
			(polygon
				(pts
					(xy 170.053 -125.349) (xy 170.053 -125.857) (xy 169.672 -125.857) (xy 169.672 -125.349)
				)
			)
		)
		(zone
			(layer "B.Cu")
			(hatch none 0.5)
			(connect_pads
				(clearance 0)
			)
			(min_thickness 0.25)
			(keepout
				(tracks not_allowed)
				(vias allowed)
				(pads allowed)
				(copperpour not_allowed)
				(footprints allowed)
			)
			(placement
				(enabled no)
				(sheetname "")
			)
			(fill
				(thermal_gap 0.5)
				(thermal_bridge_width 0.5)
				(island_removal_mode 0)
			)
			(polygon
				(pts
					(xy 170.053 -125.349) (xy 170.053 -125.857) (xy 169.672 -125.857) (xy 169.672 -125.349)
				)
			)
		)
	)
)
